(kicad_pcb
	(version 20260206)
	(generator "pcbnew")
	(generator_version "10.0")
	(general
		(thickness 1.6)
		(legacy_teardrops no)
	)
	(paper "A4")
	(title_block
		(title "01162023_DA0F0TEBIF0_F0T_Expander_BD_F_brd_V02_OCP.brd")
		(comment 1 "Grand Teton / footprints 4977-4981 of 9728")
	)
	(layers
		(0 "F.Cu" signal "TOP")
		(4 "In1.Cu" signal "GND")
		(6 "In2.Cu" signal "VCC")
		(8 "In3.Cu" signal "VCC1")
		(10 "In4.Cu" signal "GND1")
		(12 "In5.Cu" signal "IN1")
		(14 "In6.Cu" signal "GND2")
		(16 "In7.Cu" signal "IN2")
		(18 "In8.Cu" signal "GND3")
		(20 "In9.Cu" signal "IN3")
		(22 "In10.Cu" signal "GND4")
		(24 "In11.Cu" signal "IN4")
		(26 "In12.Cu" signal "GND5")
		(28 "In13.Cu" signal "IN5")
		(30 "In14.Cu" signal "GND6")
		(32 "In15.Cu" signal "IN6")
		(34 "In16.Cu" signal "GND7")
		(2 "B.Cu" signal "BOTTOM")
		(9 "F.Adhes" user "F.Adhesive")
		(11 "B.Adhes" user "B.Adhesive")
		(13 "F.Paste" user "Package Geometry/Pastemask Top")
		(15 "B.Paste" user "Package Geometry/Pastemask Bottom")
		(5 "F.SilkS" user "Ref Des/Silkscreen Top")
		(7 "B.SilkS" user "Ref Des/Silkscreen Bottom")
		(1 "F.Mask" user "Board Geometry/Soldermask Top")
		(3 "B.Mask" user "Board Geometry/Soldermask Bottom")
		(17 "Dwgs.User" user "User.Drawings")
		(19 "Cmts.User" user "User.Comments")
		(21 "Eco1.User" user "User.Eco1")
		(23 "Eco2.User" user "User.Eco2")
		(25 "Edge.Cuts" user "Board Geometry/Outline")
		(27 "Margin" user)
		(31 "F.CrtYd" user "Package Geometry/Place Bound Top")
		(29 "B.CrtYd" user "Package Geometry/Place Bound Bottom")
		(35 "F.Fab" user "Ref Des/Assembly Top")
		(33 "B.Fab" user "Ref Des/Assembly Bottom")
	)
	(footprint ""
		(layer "F.Cu")
		(at 73.885552 -27.092148 -90)
		(property "Reference" "R5735"
			(at 0 0 270)
			(layer "F.SilkS")
			(hide yes)
			(effects
				(font
					(size 1.27 1.27)
				)
			)
		)
		(property "Value" ""
			(at 0 0 270)
			(layer "F.Fab")
			(effects
				(font
					(size 1.27 1.27)
				)
			)
		)
		(duplicate_pad_numbers_are_jumpers no)
		(fp_line
			(start -0.7874 0.4064)
			(end -0.7874 -0.4064)
			(stroke
				(width 0.1524)
				(type default)
			)
			(layer "F.SilkS")
		)
		(fp_line
			(start 0.7874 0.4064)
			(end -0.7874 0.4064)
			(stroke
				(width 0.1524)
				(type default)
			)
			(layer "F.SilkS")
		)
		(fp_line
			(start -0.7874 -0.4064)
			(end 0.7874 -0.4064)
			(stroke
				(width 0.1524)
				(type default)
			)
			(layer "F.SilkS")
		)
		(fp_line
			(start 0.7874 -0.4064)
			(end 0.7874 0.4064)
			(stroke
				(width 0.1524)
				(type default)
			)
			(layer "F.SilkS")
		)
		(fp_line
			(start -0.67945 0.3048)
			(end -0.67945 -0.305054)
			(stroke
				(width 0.1)
				(type default)
			)
			(layer "F.Fab")
		)
		(fp_line
			(start -0.12065 0.3048)
			(end -0.67945 0.3048)
			(stroke
				(width 0.1)
				(type default)
			)
			(layer "F.Fab")
		)
		(fp_line
			(start 0.120396 0.3048)
			(end 0.120396 0.2794)
			(stroke
				(width 0.1)
				(type default)
			)
			(layer "F.Fab")
		)
		(fp_line
			(start 0.67945 0.3048)
			(end 0.120396 0.3048)
			(stroke
				(width 0.1)
				(type default)
			)
			(layer "F.Fab")
		)
		(fp_line
			(start -0.12065 0.2794)
			(end -0.12065 0.3048)
			(stroke
				(width 0.1)
				(type default)
			)
			(layer "F.Fab")
		)
		(fp_line
			(start 0.120396 0.2794)
			(end -0.12065 0.2794)
			(stroke
				(width 0.1)
				(type default)
			)
			(layer "F.Fab")
		)
		(fp_line
			(start -0.12065 -0.2794)
			(end 0.12065 -0.2794)
			(stroke
				(width 0.1)
				(type default)
			)
			(layer "F.Fab")
		)
		(fp_line
			(start 0.12065 -0.2794)
			(end 0.12065 -0.3048)
			(stroke
				(width 0.1)
				(type default)
			)
			(layer "F.Fab")
		)
		(fp_line
			(start 0.12065 -0.3048)
			(end 0.67945 -0.3048)
			(stroke
				(width 0.1)
				(type default)
			)
			(layer "F.Fab")
		)
		(fp_line
			(start 0.67945 -0.3048)
			(end 0.67945 0.3048)
			(stroke
				(width 0.1)
				(type default)
			)
			(layer "F.Fab")
		)
		(fp_line
			(start -0.67945 -0.305054)
			(end -0.12065 -0.305054)
			(stroke
				(width 0.1)
				(type default)
			)
			(layer "F.Fab")
		)
		(fp_line
			(start -0.12065 -0.305054)
			(end -0.12065 -0.2794)
			(stroke
				(width 0.1)
				(type default)
			)
			(layer "F.Fab")
		)
		(pad "1" smd circle
			(at -0.40005 0 270)
			(size 0 0)
			(layers "F.Cu" "F.Mask" "F.Paste")
			(net "P3V3_SSD2")
		)
		(pad "2" smd circle
			(at 0.40005 0 270)
			(size 0 0)
			(layers "F.Cu" "F.Mask" "F.Paste")
			(net "SSD2_LED_ISO_N")
		)
	)
	(footprint ""
		(layer "F.Cu")
		(at 259.590286 -250.070874 -90)
		(property "Reference" "R1341"
			(at 0 0 270)
			(layer "F.SilkS")
			(hide yes)
			(effects
				(font
					(size 1.27 1.27)
				)
			)
		)
		(property "Value" ""
			(at 0 0 270)
			(layer "F.Fab")
			(effects
				(font
					(size 1.27 1.27)
				)
			)
		)
		(duplicate_pad_numbers_are_jumpers no)
		(fp_line
			(start -0.7874 0.4064)
			(end -0.7874 -0.4064)
			(stroke
				(width 0.1524)
				(type default)
			)
			(layer "F.SilkS")
		)
		(fp_line
			(start 0.7874 0.4064)
			(end -0.7874 0.4064)
			(stroke
				(width 0.1524)
				(type default)
			)
			(layer "F.SilkS")
		)
		(fp_line
			(start -0.7874 -0.4064)
			(end 0.7874 -0.4064)
			(stroke
				(width 0.1524)
				(type default)
			)
			(layer "F.SilkS")
		)
		(fp_line
			(start 0.7874 -0.4064)
			(end 0.7874 0.4064)
			(stroke
				(width 0.1524)
				(type default)
			)
			(layer "F.SilkS")
		)
		(fp_line
			(start -0.67945 0.3048)
			(end -0.67945 -0.305054)
			(stroke
				(width 0.1)
				(type default)
			)
			(layer "F.Fab")
		)
		(fp_line
			(start -0.12065 0.3048)
			(end -0.67945 0.3048)
			(stroke
				(width 0.1)
				(type default)
			)
			(layer "F.Fab")
		)
		(fp_line
			(start 0.120396 0.3048)
			(end 0.120396 0.2794)
			(stroke
				(width 0.1)
				(type default)
			)
			(layer "F.Fab")
		)
		(fp_line
			(start 0.67945 0.3048)
			(end 0.120396 0.3048)
			(stroke
				(width 0.1)
				(type default)
			)
			(layer "F.Fab")
		)
		(fp_line
			(start -0.12065 0.2794)
			(end -0.12065 0.3048)
			(stroke
				(width 0.1)
				(type default)
			)
			(layer "F.Fab")
		)
		(fp_line
			(start 0.120396 0.2794)
			(end -0.12065 0.2794)
			(stroke
				(width 0.1)
				(type default)
			)
			(layer "F.Fab")
		)
		(fp_line
			(start -0.12065 -0.2794)
			(end 0.12065 -0.2794)
			(stroke
				(width 0.1)
				(type default)
			)
			(layer "F.Fab")
		)
		(fp_line
			(start 0.12065 -0.2794)
			(end 0.12065 -0.3048)
			(stroke
				(width 0.1)
				(type default)
			)
			(layer "F.Fab")
		)
		(fp_line
			(start 0.12065 -0.3048)
			(end 0.67945 -0.3048)
			(stroke
				(width 0.1)
				(type default)
			)
			(layer "F.Fab")
		)
		(fp_line
			(start 0.67945 -0.3048)
			(end 0.67945 0.3048)
			(stroke
				(width 0.1)
				(type default)
			)
			(layer "F.Fab")
		)
		(fp_line
			(start -0.67945 -0.305054)
			(end -0.12065 -0.305054)
			(stroke
				(width 0.1)
				(type default)
			)
			(layer "F.Fab")
		)
		(fp_line
			(start -0.12065 -0.305054)
			(end -0.12065 -0.2794)
			(stroke
				(width 0.1)
				(type default)
			)
			(layer "F.Fab")
		)
		(pad "1" smd circle
			(at -0.40005 0 270)
			(size 0 0)
			(layers "F.Cu" "F.Mask" "F.Paste")
			(net "PEX2_MODE_SEL5")
		)
		(pad "2" smd circle
			(at 0.40005 0 270)
			(size 0 0)
			(layers "F.Cu" "F.Mask" "F.Paste")
			(net "P1V8_PEX")
		)
	)
	(footprint ""
		(layer "F.Cu")
		(at 331.175614 -118.467886)
		(property "Reference" "PC471"
			(at 0 0 0)
			(layer "F.SilkS")
			(hide yes)
			(effects
				(font
					(size 1.27 1.27)
				)
			)
		)
		(property "Value" ""
			(at 0 0 0)
			(layer "F.Fab")
			(effects
				(font
					(size 1.27 1.27)
				)
			)
		)
		(duplicate_pad_numbers_are_jumpers no)
		(fp_line
			(start -0.7874 -0.4064)
			(end 0.7874 -0.4064)
			(stroke
				(width 0.1524)
				(type default)
			)
			(layer "F.SilkS")
		)
		(fp_line
			(start -0.7874 0.4064)
			(end -0.7874 -0.4064)
			(stroke
				(width 0.1524)
				(type default)
			)
			(layer "F.SilkS")
		)
		(fp_line
			(start 0.7874 -0.4064)
			(end 0.7874 0.4064)
			(stroke
				(width 0.1524)
				(type default)
			)
			(layer "F.SilkS")
		)
		(fp_line
			(start 0.7874 0.4064)
			(end -0.7874 0.4064)
			(stroke
				(width 0.1524)
				(type default)
			)
			(layer "F.SilkS")
		)
		(fp_line
			(start -0.67945 -0.305054)
			(end -0.12065 -0.305054)
			(stroke
				(width 0.1)
				(type default)
			)
			(layer "F.Fab")
		)
		(fp_line
			(start -0.67945 0.3048)
			(end -0.67945 -0.305054)
			(stroke
				(width 0.1)
				(type default)
			)
			(layer "F.Fab")
		)
		(fp_line
			(start -0.12065 -0.305054)
			(end -0.12065 -0.2794)
			(stroke
				(width 0.1)
				(type default)
			)
			(layer "F.Fab")
		)
		(fp_line
			(start -0.12065 -0.2794)
			(end 0.12065 -0.2794)
			(stroke
				(width 0.1)
				(type default)
			)
			(layer "F.Fab")
		)
		(fp_line
			(start -0.12065 0.2794)
			(end -0.12065 0.3048)
			(stroke
				(width 0.1)
				(type default)
			)
			(layer "F.Fab")
		)
		(fp_line
			(start -0.12065 0.3048)
			(end -0.67945 0.3048)
			(stroke
				(width 0.1)
				(type default)
			)
			(layer "F.Fab")
		)
		(fp_line
			(start 0.120396 0.2794)
			(end -0.12065 0.2794)
			(stroke
				(width 0.1)
				(type default)
			)
			(layer "F.Fab")
		)
		(fp_line
			(start 0.120396 0.3048)
			(end 0.120396 0.2794)
			(stroke
				(width 0.1)
				(type default)
			)
			(layer "F.Fab")
		)
		(fp_line
			(start 0.12065 -0.3048)
			(end 0.67945 -0.3048)
			(stroke
				(width 0.1)
				(type default)
			)
			(layer "F.Fab")
		)
		(fp_line
			(start 0.12065 -0.2794)
			(end 0.12065 -0.3048)
			(stroke
				(width 0.1)
				(type default)
			)
			(layer "F.Fab")
		)
		(fp_line
			(start 0.67945 -0.3048)
			(end 0.67945 0.3048)
			(stroke
				(width 0.1)
				(type default)
			)
			(layer "F.Fab")
		)
		(fp_line
			(start 0.67945 0.3048)
			(end 0.120396 0.3048)
			(stroke
				(width 0.1)
				(type default)
			)
			(layer "F.Fab")
		)
		(pad "1" smd circle
			(at -0.40005 0)
			(size 0 0)
			(layers "F.Cu" "F.Mask" "F.Paste")
			(net "P3V3_NIC5_SS")
		)
		(pad "2" smd circle
			(at 0.40005 0)
			(size 0 0)
			(layers "F.Cu" "F.Mask" "F.Paste")
			(net "GND")
		)
	)
	(footprint ""
		(layer "F.Cu")
		(at 99.97948 -385.577842 -90)
		(property "Reference" "R5445"
			(at 0 0 270)
			(layer "F.SilkS")
			(hide yes)
			(effects
				(font
					(size 1.27 1.27)
				)
			)
		)
		(property "Value" ""
			(at 0 0 270)
			(layer "F.Fab")
			(effects
				(font
					(size 1.27 1.27)
				)
			)
		)
		(duplicate_pad_numbers_are_jumpers no)
		(fp_line
			(start 0.7874 0.4064)
			(end -0.7874 0.4064)
			(stroke
				(width 0.1524)
				(type default)
			)
			(layer "F.SilkS")
		)
		(fp_line
			(start -0.7874 -0.4064)
			(end 0.007112 -0.4064)
			(stroke
				(width 0.1524)
				(type default)
			)
			(layer "F.SilkS")
		)
		(fp_line
			(start 0.7874 -0.4064)
			(end 0.7874 0.4064)
			(stroke
				(width 0.1524)
				(type default)
			)
			(layer "F.SilkS")
		)
		(fp_line
			(start -0.67945 0.3048)
			(end -0.67945 -0.305054)
			(stroke
				(width 0.1)
				(type default)
			)
			(layer "F.Fab")
		)
		(fp_line
			(start -0.12065 0.3048)
			(end -0.67945 0.3048)
			(stroke
				(width 0.1)
				(type default)
			)
			(layer "F.Fab")
		)
		(fp_line
			(start 0.120396 0.3048)
			(end 0.120396 0.2794)
			(stroke
				(width 0.1)
				(type default)
			)
			(layer "F.Fab")
		)
		(fp_line
			(start 0.67945 0.3048)
			(end 0.120396 0.3048)
			(stroke
				(width 0.1)
				(type default)
			)
			(layer "F.Fab")
		)
		(fp_line
			(start -0.12065 0.2794)
			(end -0.12065 0.3048)
			(stroke
				(width 0.1)
				(type default)
			)
			(layer "F.Fab")
		)
		(fp_line
			(start 0.120396 0.2794)
			(end -0.12065 0.2794)
			(stroke
				(width 0.1)
				(type default)
			)
			(layer "F.Fab")
		)
		(fp_line
			(start -0.12065 -0.2794)
			(end 0.12065 -0.2794)
			(stroke
				(width 0.1)
				(type default)
			)
			(layer "F.Fab")
		)
		(fp_line
			(start 0.12065 -0.2794)
			(end 0.12065 -0.3048)
			(stroke
				(width 0.1)
				(type default)
			)
			(layer "F.Fab")
		)
		(fp_line
			(start 0.12065 -0.3048)
			(end 0.67945 -0.3048)
			(stroke
				(width 0.1)
				(type default)
			)
			(layer "F.Fab")
		)
		(fp_line
			(start 0.67945 -0.3048)
			(end 0.67945 0.3048)
			(stroke
				(width 0.1)
				(type default)
			)
			(layer "F.Fab")
		)
		(fp_line
			(start -0.67945 -0.305054)
			(end -0.12065 -0.305054)
			(stroke
				(width 0.1)
				(type default)
			)
			(layer "F.Fab")
		)
		(fp_line
			(start -0.12065 -0.305054)
			(end -0.12065 -0.2794)
			(stroke
				(width 0.1)
				(type default)
			)
			(layer "F.Fab")
		)
		(pad "1" smd rect
			(at -0.40005 0 90)
			(size 0.4572 0.508)
			(layers "F.Cu" "F.Mask" "F.Paste")
			(net "USB2_MB_BMC_R_DN")
		)
		(pad "2" smd rect
			(at 0.40005 0 90)
			(size 0.4572 0.508)
			(layers "F.Cu" "F.Mask" "F.Paste")
			(net "USB2_MB_BMC_DN")
		)
	)
	(footprint ""
		(layer "F.Cu")
		(at 163.047426 -20.35556)
		(property "Reference" "C3908"
			(at 0 0 0)
			(layer "F.SilkS")
			(hide yes)
			(effects
				(font
					(size 1.27 1.27)
				)
			)
		)
		(property "Value" ""
			(at 0 0 0)
			(layer "F.Fab")
			(effects
				(font
					(size 1.27 1.27)
				)
			)
		)
		(duplicate_pad_numbers_are_jumpers no)
		(fp_line
			(start -0.7874 -0.4064)
			(end 0.7874 -0.4064)
			(stroke
				(width 0.1524)
				(type default)
			)
			(layer "F.SilkS")
		)
		(fp_line
			(start -0.7874 0.4064)
			(end -0.7874 -0.4064)
			(stroke
				(width 0.1524)
				(type default)
			)
			(layer "F.SilkS")
		)
		(fp_line
			(start 0.7874 -0.4064)
			(end 0.7874 0.4064)
			(stroke
				(width 0.1524)
				(type default)
			)
			(layer "F.SilkS")
		)
		(fp_line
			(start 0.7874 0.4064)
			(end -0.7874 0.4064)
			(stroke
				(width 0.1524)
				(type default)
			)
			(layer "F.SilkS")
		)
		(fp_line
			(start -0.67945 -0.305054)
			(end -0.12065 -0.305054)
			(stroke
				(width 0.1)
				(type default)
			)
			(layer "F.Fab")
		)
		(fp_line
			(start -0.67945 0.3048)
			(end -0.67945 -0.305054)
			(stroke
				(width 0.1)
				(type default)
			)
			(layer "F.Fab")
		)
		(fp_line
			(start -0.12065 -0.305054)
			(end -0.12065 -0.2794)
			(stroke
				(width 0.1)
				(type default)
			)
			(layer "F.Fab")
		)
		(fp_line
			(start -0.12065 -0.2794)
			(end 0.12065 -0.2794)
			(stroke
				(width 0.1)
				(type default)
			)
			(layer "F.Fab")
		)
		(fp_line
			(start -0.12065 0.2794)
			(end -0.12065 0.3048)
			(stroke
				(width 0.1)
				(type default)
			)
			(layer "F.Fab")
		)
		(fp_line
			(start -0.12065 0.3048)
			(end -0.67945 0.3048)
			(stroke
				(width 0.1)
				(type default)
			)
			(layer "F.Fab")
		)
		(fp_line
			(start 0.120396 0.2794)
			(end -0.12065 0.2794)
			(stroke
				(width 0.1)
				(type default)
			)
			(layer "F.Fab")
		)
		(fp_line
			(start 0.120396 0.3048)
			(end 0.120396 0.2794)
			(stroke
				(width 0.1)
				(type default)
			)
			(layer "F.Fab")
		)
		(fp_line
			(start 0.12065 -0.3048)
			(end 0.67945 -0.3048)
			(stroke
				(width 0.1)
				(type default)
			)
			(layer "F.Fab")
		)
		(fp_line
			(start 0.12065 -0.2794)
			(end 0.12065 -0.3048)
			(stroke
				(width 0.1)
				(type default)
			)
			(layer "F.Fab")
		)
		(fp_line
			(start 0.67945 -0.3048)
			(end 0.67945 0.3048)
			(stroke
				(width 0.1)
				(type default)
			)
			(layer "F.Fab")
		)
		(fp_line
			(start 0.67945 0.3048)
			(end 0.120396 0.3048)
			(stroke
				(width 0.1)
				(type default)
			)
			(layer "F.Fab")
		)
		(pad "1" smd circle
			(at -0.40005 0)
			(size 0 0)
			(layers "F.Cu" "F.Mask" "F.Paste")
			(net "P12V_SSD5")
		)
		(pad "2" smd circle
			(at 0.40005 0)
			(size 0 0)
			(layers "F.Cu" "F.Mask" "F.Paste")
			(net "GND")
		)
	)
)
